(kicad_pcb
	(version 20260206)
	(generator "pcbnew")
	(generator_version "10.0")
	(general
		(thickness 1.6)
		(legacy_teardrops no)
	)
	(paper "A4")
	(title_block
		(title "03242023_DA0F0TMBIJ0_F0T_Motherboard_J_brd_V01_OCP.brd")
		(comment 1 "Grand Teton / footprints 3118-3123 of 6105")
	)
	(layers
		(0 "F.Cu" signal "TOP")
		(4 "In1.Cu" signal "GND")
		(6 "In2.Cu" signal "IN1")
		(8 "In3.Cu" signal "GND1")
		(10 "In4.Cu" signal "IN2")
		(12 "In5.Cu" signal "GND2")
		(14 "In6.Cu" signal "IN3")
		(16 "In7.Cu" signal "GND3")
		(18 "In8.Cu" signal "VCC")
		(20 "In9.Cu" signal "VCC1")
		(22 "In10.Cu" signal "GND4")
		(24 "In11.Cu" signal "IN4")
		(26 "In12.Cu" signal "GND5")
		(28 "In13.Cu" signal "IN5")
		(30 "In14.Cu" signal "GND6")
		(32 "In15.Cu" signal "IN6")
		(34 "In16.Cu" signal "GND7")
		(2 "B.Cu" signal "BOTTOM")
		(9 "F.Adhes" user "F.Adhesive")
		(11 "B.Adhes" user "B.Adhesive")
		(13 "F.Paste" user "Package Geometry/Pastemask Top")
		(15 "B.Paste" user "Package Geometry/Pastemask Bottom")
		(5 "F.SilkS" user "Ref Des/Silkscreen Top")
		(7 "B.SilkS" user "Ref Des/Silkscreen Bottom")
		(1 "F.Mask" user "Board Geometry/Soldermask Top")
		(3 "B.Mask" user "Board Geometry/Soldermask Bottom")
		(17 "Dwgs.User" user "User.Drawings")
		(19 "Cmts.User" user "User.Comments")
		(21 "Eco1.User" user "User.Eco1")
		(23 "Eco2.User" user "User.Eco2")
		(25 "Edge.Cuts" user "Board Geometry/Outline")
		(27 "Margin" user)
		(31 "F.CrtYd" user "Package Geometry/Place Bound Top")
		(29 "B.CrtYd" user "Package Geometry/Place Bound Bottom")
		(35 "F.Fab" user "Ref Des/Assembly Top")
		(33 "B.Fab" user "Ref Des/Assembly Bottom")
	)
	(footprint ""
		(layer "F.Cu")
		(at 385.716272 -63.423292 180)
		(property "Reference" "R1026"
			(at 0 0 180)
			(layer "F.SilkS")
			(hide yes)
			(effects
				(font
					(size 1.27 1.27)
				)
			)
		)
		(property "Value" ""
			(at 0 0 180)
			(layer "F.Fab")
			(effects
				(font
					(size 1.27 1.27)
				)
			)
		)
		(duplicate_pad_numbers_are_jumpers no)
		(fp_line
			(start 0.7874 0.4064)
			(end -0.7874 0.4064)
			(stroke
				(width 0.1524)
				(type default)
			)
			(layer "F.SilkS")
		)
		(fp_line
			(start 0.7874 -0.4064)
			(end 0.7874 0.4064)
			(stroke
				(width 0.1524)
				(type default)
			)
			(layer "F.SilkS")
		)
		(fp_line
			(start -0.7874 0.4064)
			(end -0.7874 -0.4064)
			(stroke
				(width 0.1524)
				(type default)
			)
			(layer "F.SilkS")
		)
		(fp_line
			(start -0.7874 -0.4064)
			(end 0.7874 -0.4064)
			(stroke
				(width 0.1524)
				(type default)
			)
			(layer "F.SilkS")
		)
		(fp_line
			(start 0.67945 0.3048)
			(end 0.120396 0.3048)
			(stroke
				(width 0.1)
				(type default)
			)
			(layer "F.Fab")
		)
		(fp_line
			(start 0.67945 -0.3048)
			(end 0.67945 0.3048)
			(stroke
				(width 0.1)
				(type default)
			)
			(layer "F.Fab")
		)
		(fp_line
			(start 0.12065 -0.2794)
			(end 0.12065 -0.3048)
			(stroke
				(width 0.1)
				(type default)
			)
			(layer "F.Fab")
		)
		(fp_line
			(start 0.12065 -0.3048)
			(end 0.67945 -0.3048)
			(stroke
				(width 0.1)
				(type default)
			)
			(layer "F.Fab")
		)
		(fp_line
			(start 0.120396 0.3048)
			(end 0.120396 0.2794)
			(stroke
				(width 0.1)
				(type default)
			)
			(layer "F.Fab")
		)
		(fp_line
			(start 0.120396 0.2794)
			(end -0.12065 0.2794)
			(stroke
				(width 0.1)
				(type default)
			)
			(layer "F.Fab")
		)
		(fp_line
			(start -0.12065 0.3048)
			(end -0.67945 0.3048)
			(stroke
				(width 0.1)
				(type default)
			)
			(layer "F.Fab")
		)
		(fp_line
			(start -0.12065 0.2794)
			(end -0.12065 0.3048)
			(stroke
				(width 0.1)
				(type default)
			)
			(layer "F.Fab")
		)
		(fp_line
			(start -0.12065 -0.2794)
			(end 0.12065 -0.2794)
			(stroke
				(width 0.1)
				(type default)
			)
			(layer "F.Fab")
		)
		(fp_line
			(start -0.12065 -0.305054)
			(end -0.12065 -0.2794)
			(stroke
				(width 0.1)
				(type default)
			)
			(layer "F.Fab")
		)
		(fp_line
			(start -0.67945 0.3048)
			(end -0.67945 -0.305054)
			(stroke
				(width 0.1)
				(type default)
			)
			(layer "F.Fab")
		)
		(fp_line
			(start -0.67945 -0.305054)
			(end -0.12065 -0.305054)
			(stroke
				(width 0.1)
				(type default)
			)
			(layer "F.Fab")
		)
		(pad "1" smd circle
			(at -0.40005 0 180)
			(size 0 0)
			(layers "F.Cu" "F.Mask" "F.Paste")
			(net "JTAG_DBP_PMODE")
		)
		(pad "2" smd circle
			(at 0.40005 0 180)
			(size 0 0)
			(layers "F.Cu" "F.Mask" "F.Paste")
			(net "P1V05_PCH_AUX")
		)
	)
	(footprint ""
		(layer "F.Cu")
		(at 440.38012 -100.27158 90)
		(property "Reference" "R4745"
			(at 0 0 90)
			(layer "F.SilkS")
			(hide yes)
			(effects
				(font
					(size 1.27 1.27)
				)
			)
		)
		(property "Value" ""
			(at 0 0 90)
			(layer "F.Fab")
			(effects
				(font
					(size 1.27 1.27)
				)
			)
		)
		(duplicate_pad_numbers_are_jumpers no)
		(fp_line
			(start 0.7874 -0.4064)
			(end 0.7874 0.4064)
			(stroke
				(width 0.1524)
				(type default)
			)
			(layer "F.SilkS")
		)
		(fp_line
			(start -0.7874 -0.4064)
			(end 0.7874 -0.4064)
			(stroke
				(width 0.1524)
				(type default)
			)
			(layer "F.SilkS")
		)
		(fp_line
			(start 0.7874 0.4064)
			(end -0.7874 0.4064)
			(stroke
				(width 0.1524)
				(type default)
			)
			(layer "F.SilkS")
		)
		(fp_line
			(start -0.7874 0.4064)
			(end -0.7874 -0.4064)
			(stroke
				(width 0.1524)
				(type default)
			)
			(layer "F.SilkS")
		)
		(fp_line
			(start -0.12065 -0.305054)
			(end -0.12065 -0.2794)
			(stroke
				(width 0.1)
				(type default)
			)
			(layer "F.Fab")
		)
		(fp_line
			(start -0.67945 -0.305054)
			(end -0.12065 -0.305054)
			(stroke
				(width 0.1)
				(type default)
			)
			(layer "F.Fab")
		)
		(fp_line
			(start 0.67945 -0.3048)
			(end 0.67945 0.3048)
			(stroke
				(width 0.1)
				(type default)
			)
			(layer "F.Fab")
		)
		(fp_line
			(start 0.12065 -0.3048)
			(end 0.67945 -0.3048)
			(stroke
				(width 0.1)
				(type default)
			)
			(layer "F.Fab")
		)
		(fp_line
			(start 0.12065 -0.2794)
			(end 0.12065 -0.3048)
			(stroke
				(width 0.1)
				(type default)
			)
			(layer "F.Fab")
		)
		(fp_line
			(start -0.12065 -0.2794)
			(end 0.12065 -0.2794)
			(stroke
				(width 0.1)
				(type default)
			)
			(layer "F.Fab")
		)
		(fp_line
			(start 0.120396 0.2794)
			(end -0.12065 0.2794)
			(stroke
				(width 0.1)
				(type default)
			)
			(layer "F.Fab")
		)
		(fp_line
			(start -0.12065 0.2794)
			(end -0.12065 0.3048)
			(stroke
				(width 0.1)
				(type default)
			)
			(layer "F.Fab")
		)
		(fp_line
			(start 0.67945 0.3048)
			(end 0.120396 0.3048)
			(stroke
				(width 0.1)
				(type default)
			)
			(layer "F.Fab")
		)
		(fp_line
			(start 0.120396 0.3048)
			(end 0.120396 0.2794)
			(stroke
				(width 0.1)
				(type default)
			)
			(layer "F.Fab")
		)
		(fp_line
			(start -0.12065 0.3048)
			(end -0.67945 0.3048)
			(stroke
				(width 0.1)
				(type default)
			)
			(layer "F.Fab")
		)
		(fp_line
			(start -0.67945 0.3048)
			(end -0.67945 -0.305054)
			(stroke
				(width 0.1)
				(type default)
			)
			(layer "F.Fab")
		)
		(pad "1" smd circle
			(at -0.40005 0 90)
			(size 0 0)
			(layers "F.Cu" "F.Mask" "F.Paste")
			(net "P3V3_AUX")
		)
		(pad "2" smd circle
			(at 0.40005 0 90)
			(size 0 0)
			(layers "F.Cu" "F.Mask" "F.Paste")
			(net "OCP_SFF_AUX_PWR_PLD_EN_R")
		)
	)
	(footprint ""
		(layer "F.Cu")
		(at 69.042534 -65.082674 -90)
		(property "Reference" "R3083"
			(at 0 0 270)
			(layer "F.SilkS")
			(hide yes)
			(effects
				(font
					(size 1.27 1.27)
				)
			)
		)
		(property "Value" ""
			(at 0 0 270)
			(layer "F.Fab")
			(effects
				(font
					(size 1.27 1.27)
				)
			)
		)
		(duplicate_pad_numbers_are_jumpers no)
		(fp_line
			(start -0.7874 0.4064)
			(end -0.7874 -0.4064)
			(stroke
				(width 0.1524)
				(type default)
			)
			(layer "F.SilkS")
		)
		(fp_line
			(start 0.7874 0.4064)
			(end -0.7874 0.4064)
			(stroke
				(width 0.1524)
				(type default)
			)
			(layer "F.SilkS")
		)
		(fp_line
			(start -0.7874 -0.4064)
			(end 0.7874 -0.4064)
			(stroke
				(width 0.1524)
				(type default)
			)
			(layer "F.SilkS")
		)
		(fp_line
			(start 0.7874 -0.4064)
			(end 0.7874 0.4064)
			(stroke
				(width 0.1524)
				(type default)
			)
			(layer "F.SilkS")
		)
		(fp_line
			(start -0.67945 0.3048)
			(end -0.67945 -0.305054)
			(stroke
				(width 0.1)
				(type default)
			)
			(layer "F.Fab")
		)
		(fp_line
			(start -0.12065 0.3048)
			(end -0.67945 0.3048)
			(stroke
				(width 0.1)
				(type default)
			)
			(layer "F.Fab")
		)
		(fp_line
			(start 0.120396 0.3048)
			(end 0.120396 0.2794)
			(stroke
				(width 0.1)
				(type default)
			)
			(layer "F.Fab")
		)
		(fp_line
			(start 0.67945 0.3048)
			(end 0.120396 0.3048)
			(stroke
				(width 0.1)
				(type default)
			)
			(layer "F.Fab")
		)
		(fp_line
			(start -0.12065 0.2794)
			(end -0.12065 0.3048)
			(stroke
				(width 0.1)
				(type default)
			)
			(layer "F.Fab")
		)
		(fp_line
			(start 0.120396 0.2794)
			(end -0.12065 0.2794)
			(stroke
				(width 0.1)
				(type default)
			)
			(layer "F.Fab")
		)
		(fp_line
			(start -0.12065 -0.2794)
			(end 0.12065 -0.2794)
			(stroke
				(width 0.1)
				(type default)
			)
			(layer "F.Fab")
		)
		(fp_line
			(start 0.12065 -0.2794)
			(end 0.12065 -0.3048)
			(stroke
				(width 0.1)
				(type default)
			)
			(layer "F.Fab")
		)
		(fp_line
			(start 0.12065 -0.3048)
			(end 0.67945 -0.3048)
			(stroke
				(width 0.1)
				(type default)
			)
			(layer "F.Fab")
		)
		(fp_line
			(start 0.67945 -0.3048)
			(end 0.67945 0.3048)
			(stroke
				(width 0.1)
				(type default)
			)
			(layer "F.Fab")
		)
		(fp_line
			(start -0.67945 -0.305054)
			(end -0.12065 -0.305054)
			(stroke
				(width 0.1)
				(type default)
			)
			(layer "F.Fab")
		)
		(fp_line
			(start -0.12065 -0.305054)
			(end -0.12065 -0.2794)
			(stroke
				(width 0.1)
				(type default)
			)
			(layer "F.Fab")
		)
		(pad "1" smd circle
			(at -0.40005 0 270)
			(size 0 0)
			(layers "F.Cu" "F.Mask" "F.Paste")
			(net "LED_RST_PLD_CPU1_DRAM_EF_N")
		)
		(pad "2" smd circle
			(at 0.40005 0 270)
			(size 0 0)
			(layers "F.Cu" "F.Mask" "F.Paste")
			(net "P3V3_AUX")
		)
	)
	(footprint ""
		(layer "F.Cu")
		(at 160.83788 -118.836948 180)
		(property "Reference" "R1409"
			(at 0 0 180)
			(layer "F.SilkS")
			(hide yes)
			(effects
				(font
					(size 1.27 1.27)
				)
			)
		)
		(property "Value" ""
			(at 0 0 180)
			(layer "F.Fab")
			(effects
				(font
					(size 1.27 1.27)
				)
			)
		)
		(duplicate_pad_numbers_are_jumpers no)
		(fp_line
			(start 0.7874 0.4064)
			(end -0.7874 0.4064)
			(stroke
				(width 0.1524)
				(type default)
			)
			(layer "F.SilkS")
		)
		(fp_line
			(start 0.7874 -0.4064)
			(end 0.7874 0.4064)
			(stroke
				(width 0.1524)
				(type default)
			)
			(layer "F.SilkS")
		)
		(fp_line
			(start -0.7874 0.4064)
			(end -0.7874 -0.4064)
			(stroke
				(width 0.1524)
				(type default)
			)
			(layer "F.SilkS")
		)
		(fp_line
			(start -0.7874 -0.4064)
			(end 0.7874 -0.4064)
			(stroke
				(width 0.1524)
				(type default)
			)
			(layer "F.SilkS")
		)
		(fp_line
			(start 0.67945 0.3048)
			(end 0.120396 0.3048)
			(stroke
				(width 0.1)
				(type default)
			)
			(layer "F.Fab")
		)
		(fp_line
			(start 0.67945 -0.3048)
			(end 0.67945 0.3048)
			(stroke
				(width 0.1)
				(type default)
			)
			(layer "F.Fab")
		)
		(fp_line
			(start 0.12065 -0.2794)
			(end 0.12065 -0.3048)
			(stroke
				(width 0.1)
				(type default)
			)
			(layer "F.Fab")
		)
		(fp_line
			(start 0.12065 -0.3048)
			(end 0.67945 -0.3048)
			(stroke
				(width 0.1)
				(type default)
			)
			(layer "F.Fab")
		)
		(fp_line
			(start 0.120396 0.3048)
			(end 0.120396 0.2794)
			(stroke
				(width 0.1)
				(type default)
			)
			(layer "F.Fab")
		)
		(fp_line
			(start 0.120396 0.2794)
			(end -0.12065 0.2794)
			(stroke
				(width 0.1)
				(type default)
			)
			(layer "F.Fab")
		)
		(fp_line
			(start -0.12065 0.3048)
			(end -0.67945 0.3048)
			(stroke
				(width 0.1)
				(type default)
			)
			(layer "F.Fab")
		)
		(fp_line
			(start -0.12065 0.2794)
			(end -0.12065 0.3048)
			(stroke
				(width 0.1)
				(type default)
			)
			(layer "F.Fab")
		)
		(fp_line
			(start -0.12065 -0.2794)
			(end 0.12065 -0.2794)
			(stroke
				(width 0.1)
				(type default)
			)
			(layer "F.Fab")
		)
		(fp_line
			(start -0.12065 -0.305054)
			(end -0.12065 -0.2794)
			(stroke
				(width 0.1)
				(type default)
			)
			(layer "F.Fab")
		)
		(fp_line
			(start -0.67945 0.3048)
			(end -0.67945 -0.305054)
			(stroke
				(width 0.1)
				(type default)
			)
			(layer "F.Fab")
		)
		(fp_line
			(start -0.67945 -0.305054)
			(end -0.12065 -0.305054)
			(stroke
				(width 0.1)
				(type default)
			)
			(layer "F.Fab")
		)
		(pad "1" smd circle
			(at -0.40005 0 180)
			(size 0 0)
			(layers "F.Cu" "F.Mask" "F.Paste")
			(net "FM_PVCCFA_EHV_CPU0_R_EN")
		)
		(pad "2" smd circle
			(at 0.40005 0 180)
			(size 0 0)
			(layers "F.Cu" "F.Mask" "F.Paste")
			(net "GND")
		)
	)
	(footprint ""
		(layer "F.Cu")
		(at 226.733608 -402.791422 180)
		(property "Reference" "PR3991"
			(at 0 0 180)
			(layer "F.SilkS")
			(hide yes)
			(effects
				(font
					(size 1.27 1.27)
				)
			)
		)
		(property "Value" ""
			(at 0 0 180)
			(layer "F.Fab")
			(effects
				(font
					(size 1.27 1.27)
				)
			)
		)
		(duplicate_pad_numbers_are_jumpers no)
		(fp_line
			(start 0.7874 0.4064)
			(end -0.7874 0.4064)
			(stroke
				(width 0.1524)
				(type default)
			)
			(layer "F.SilkS")
		)
		(fp_line
			(start 0.7874 -0.4064)
			(end 0.7874 0.4064)
			(stroke
				(width 0.1524)
				(type default)
			)
			(layer "F.SilkS")
		)
		(fp_line
			(start -0.7874 0.4064)
			(end -0.7874 -0.4064)
			(stroke
				(width 0.1524)
				(type default)
			)
			(layer "F.SilkS")
		)
		(fp_line
			(start -0.7874 -0.4064)
			(end 0.7874 -0.4064)
			(stroke
				(width 0.1524)
				(type default)
			)
			(layer "F.SilkS")
		)
		(fp_line
			(start 0.67945 0.3048)
			(end 0.120396 0.3048)
			(stroke
				(width 0.1)
				(type default)
			)
			(layer "F.Fab")
		)
		(fp_line
			(start 0.67945 -0.3048)
			(end 0.67945 0.3048)
			(stroke
				(width 0.1)
				(type default)
			)
			(layer "F.Fab")
		)
		(fp_line
			(start 0.12065 -0.2794)
			(end 0.12065 -0.3048)
			(stroke
				(width 0.1)
				(type default)
			)
			(layer "F.Fab")
		)
		(fp_line
			(start 0.12065 -0.3048)
			(end 0.67945 -0.3048)
			(stroke
				(width 0.1)
				(type default)
			)
			(layer "F.Fab")
		)
		(fp_line
			(start 0.120396 0.3048)
			(end 0.120396 0.2794)
			(stroke
				(width 0.1)
				(type default)
			)
			(layer "F.Fab")
		)
		(fp_line
			(start 0.120396 0.2794)
			(end -0.12065 0.2794)
			(stroke
				(width 0.1)
				(type default)
			)
			(layer "F.Fab")
		)
		(fp_line
			(start -0.12065 0.3048)
			(end -0.67945 0.3048)
			(stroke
				(width 0.1)
				(type default)
			)
			(layer "F.Fab")
		)
		(fp_line
			(start -0.12065 0.2794)
			(end -0.12065 0.3048)
			(stroke
				(width 0.1)
				(type default)
			)
			(layer "F.Fab")
		)
		(fp_line
			(start -0.12065 -0.2794)
			(end 0.12065 -0.2794)
			(stroke
				(width 0.1)
				(type default)
			)
			(layer "F.Fab")
		)
		(fp_line
			(start -0.12065 -0.305054)
			(end -0.12065 -0.2794)
			(stroke
				(width 0.1)
				(type default)
			)
			(layer "F.Fab")
		)
		(fp_line
			(start -0.67945 0.3048)
			(end -0.67945 -0.305054)
			(stroke
				(width 0.1)
				(type default)
			)
			(layer "F.Fab")
		)
		(fp_line
			(start -0.67945 -0.305054)
			(end -0.12065 -0.305054)
			(stroke
				(width 0.1)
				(type default)
			)
			(layer "F.Fab")
		)
		(pad "1" smd circle
			(at -0.40005 0 180)
			(size 0 0)
			(layers "F.Cu" "F.Mask" "F.Paste")
			(net "HSC_IMON")
		)
		(pad "2" smd circle
			(at 0.40005 0 180)
			(size 0 0)
			(layers "F.Cu" "F.Mask" "F.Paste")
			(net "AGND_HSC")
		)
	)
	(footprint ""
		(layer "F.Cu")
		(at 355.236018 -245.634002 -90)
		(property "Reference" "C991"
			(at 0 0 270)
			(layer "F.SilkS")
			(hide yes)
			(effects
				(font
					(size 1.27 1.27)
				)
			)
		)
		(property "Value" ""
			(at 0 0 270)
			(layer "F.Fab")
			(effects
				(font
					(size 1.27 1.27)
				)
			)
		)
		(duplicate_pad_numbers_are_jumpers no)
		(fp_line
			(start -0.7874 0.4064)
			(end -0.7874 -0.4064)
			(stroke
				(width 0.1524)
				(type default)
			)
			(layer "F.SilkS")
		)
		(fp_line
			(start 0.7874 0.4064)
			(end -0.7874 0.4064)
			(stroke
				(width 0.1524)
				(type default)
			)
			(layer "F.SilkS")
		)
		(fp_line
			(start -0.7874 -0.4064)
			(end 0.7874 -0.4064)
			(stroke
				(width 0.1524)
				(type default)
			)
			(layer "F.SilkS")
		)
		(fp_line
			(start 0.7874 -0.4064)
			(end 0.7874 0.4064)
			(stroke
				(width 0.1524)
				(type default)
			)
			(layer "F.SilkS")
		)
		(fp_line
			(start -0.67945 0.3048)
			(end -0.67945 -0.305054)
			(stroke
				(width 0.1)
				(type default)
			)
			(layer "F.Fab")
		)
		(fp_line
			(start -0.12065 0.3048)
			(end -0.67945 0.3048)
			(stroke
				(width 0.1)
				(type default)
			)
			(layer "F.Fab")
		)
		(fp_line
			(start 0.120396 0.3048)
			(end 0.120396 0.2794)
			(stroke
				(width 0.1)
				(type default)
			)
			(layer "F.Fab")
		)
		(fp_line
			(start 0.67945 0.3048)
			(end 0.120396 0.3048)
			(stroke
				(width 0.1)
				(type default)
			)
			(layer "F.Fab")
		)
		(fp_line
			(start -0.12065 0.2794)
			(end -0.12065 0.3048)
			(stroke
				(width 0.1)
				(type default)
			)
			(layer "F.Fab")
		)
		(fp_line
			(start 0.120396 0.2794)
			(end -0.12065 0.2794)
			(stroke
				(width 0.1)
				(type default)
			)
			(layer "F.Fab")
		)
		(fp_line
			(start -0.12065 -0.2794)
			(end 0.12065 -0.2794)
			(stroke
				(width 0.1)
				(type default)
			)
			(layer "F.Fab")
		)
		(fp_line
			(start 0.12065 -0.2794)
			(end 0.12065 -0.3048)
			(stroke
				(width 0.1)
				(type default)
			)
			(layer "F.Fab")
		)
		(fp_line
			(start 0.12065 -0.3048)
			(end 0.67945 -0.3048)
			(stroke
				(width 0.1)
				(type default)
			)
			(layer "F.Fab")
		)
		(fp_line
			(start 0.67945 -0.3048)
			(end 0.67945 0.3048)
			(stroke
				(width 0.1)
				(type default)
			)
			(layer "F.Fab")
		)
		(fp_line
			(start -0.67945 -0.305054)
			(end -0.12065 -0.305054)
			(stroke
				(width 0.1)
				(type default)
			)
			(layer "F.Fab")
		)
		(fp_line
			(start -0.12065 -0.305054)
			(end -0.12065 -0.2794)
			(stroke
				(width 0.1)
				(type default)
			)
			(layer "F.Fab")
		)
		(pad "1" smd circle
			(at -0.40005 0 270)
			(size 0 0)
			(layers "F.Cu" "F.Mask" "F.Paste")
			(net "PVCCIN_CPU0")
		)
		(pad "2" smd circle
			(at 0.40005 0 270)
			(size 0 0)
			(layers "F.Cu" "F.Mask" "F.Paste")
			(net "GND")
		)
	)
)
